(kicad_pcb
	(version 20260206)
	(generator "pcbnew")
	(generator_version "10.0")
	(general
		(thickness 1.6)
		(legacy_teardrops no)
	)
	(paper "A4")
	(title_block
		(title "Wiwynn_Tioga_Pass_MB.brd")
		(comment 1 "Tioga Pass / footprints 476-483 of 4770")
	)
	(layers
		(0 "F.Cu" signal "TOP")
		(4 "In1.Cu" signal "L2GND")
		(6 "In2.Cu" signal "L3")
		(8 "In3.Cu" signal "L4GND")
		(10 "In4.Cu" signal "L5")
		(12 "In5.Cu" signal "L6GND")
		(14 "In6.Cu" signal "L7VCC")
		(16 "In7.Cu" signal "L8VCC")
		(18 "In8.Cu" signal "L9GND")
		(20 "In9.Cu" signal "L10")
		(22 "In10.Cu" signal "L11GND")
		(24 "In11.Cu" signal "L12")
		(26 "In12.Cu" signal "L13GND")
		(2 "B.Cu" signal "BOTTOM")
		(9 "F.Adhes" user "F.Adhesive")
		(11 "B.Adhes" user "B.Adhesive")
		(13 "F.Paste" user "Package Geometry/Pastemask Top")
		(15 "B.Paste" user "Package Geometry/Pastemask Bottom")
		(5 "F.SilkS" user "Ref Des/Silkscreen Top")
		(7 "B.SilkS" user "Ref Des/Silkscreen Bottom")
		(1 "F.Mask" user "Board Geometry/Soldermask Top")
		(3 "B.Mask" user "Board Geometry/Soldermask Bottom")
		(17 "Dwgs.User" user "User.Drawings")
		(19 "Cmts.User" user "User.Comments")
		(21 "Eco1.User" user "User.Eco1")
		(23 "Eco2.User" user "User.Eco2")
		(25 "Edge.Cuts" user "Board Geometry/Outline")
		(27 "Margin" user)
		(31 "F.CrtYd" user "Package Geometry/Place Bound Top")
		(29 "B.CrtYd" user "Package Geometry/Place Bound Bottom")
		(35 "F.Fab" user "Ref Des/Assembly Top")
		(33 "B.Fab" user "Ref Des/Assembly Bottom")
	)
	(footprint ""
		(layer "F.Cu")
		(at 411.444694 -131.805172 90)
		(property "Reference" "R8B5"
			(at 0 0 90)
			(layer "F.SilkS")
			(hide yes)
			(effects
				(font
					(size 1.27 1.27)
				)
			)
		)
		(property "Value" ""
			(at 0 0 90)
			(layer "F.Fab")
			(effects
				(font
					(size 1.27 1.27)
				)
			)
		)
		(duplicate_pad_numbers_are_jumpers no)
		(fp_poly
			(pts
				(xy -0.2794 -0.1016) (xy 0.2794 -0.1016) (xy 0.2794 0.9906) (xy -0.2794 0.9906)
			)
			(stroke
				(width 0)
				(type default)
			)
			(fill no)
			(layer "F.CrtYd")
		)
		(fp_line
			(start 0.2794 -0.1016)
			(end -0.2794 -0.1016)
			(stroke
				(width 0.1)
				(type default)
			)
			(layer "F.Fab")
		)
		(fp_line
			(start -0.2794 -0.1016)
			(end -0.2794 0.9906)
			(stroke
				(width 0.1)
				(type default)
			)
			(layer "F.Fab")
		)
		(fp_line
			(start 0.2794 0.9906)
			(end 0.2794 -0.1016)
			(stroke
				(width 0.1)
				(type default)
			)
			(layer "F.Fab")
		)
		(fp_line
			(start -0.2794 0.9906)
			(end 0.2794 0.9906)
			(stroke
				(width 0.1)
				(type default)
			)
			(layer "F.Fab")
		)
		(pad "1" smd rect
			(at 0 0 90)
			(size 0.508 0.508)
			(layers "F.Cu" "F.Mask" "F.Paste")
			(net "PVPP_ABC")
		)
		(pad "2" smd rect
			(at 0 0.889 90)
			(size 0.508 0.508)
			(layers "F.Cu" "F.Mask" "F.Paste")
			(net "LED_HFI0_CPU0_N")
		)
		(zone
			(layer "F.Cu")
			(hatch none 0.5)
			(connect_pads
				(clearance 0)
			)
			(min_thickness 0.25)
			(keepout
				(tracks allowed)
				(vias not_allowed)
				(pads allowed)
				(copperpour not_allowed)
				(footprints allowed)
			)
			(placement
				(enabled no)
				(sheetname "")
			)
			(fill
				(thermal_gap 0.5)
				(thermal_bridge_width 0.5)
				(island_removal_mode 0)
			)
			(polygon
				(pts
					(xy 411.698694 -131.551172) (xy 411.698694 -132.059172) (xy 412.079694 -132.059172) (xy 412.079694 -131.551172)
				)
			)
		)
		(zone
			(layer "F.Cu")
			(hatch none 0.5)
			(connect_pads
				(clearance 0)
			)
			(min_thickness 0.25)
			(keepout
				(tracks not_allowed)
				(vias allowed)
				(pads allowed)
				(copperpour not_allowed)
				(footprints allowed)
			)
			(placement
				(enabled no)
				(sheetname "")
			)
			(fill
				(thermal_gap 0.5)
				(thermal_bridge_width 0.5)
				(island_removal_mode 0)
			)
			(polygon
				(pts
					(xy 412.079694 -131.551172) (xy 412.079694 -132.059172) (xy 411.698694 -132.059172) (xy 411.698694 -131.551172)
				)
			)
		)
	)
	(footprint ""
		(layer "F.Cu")
		(at -2.8956 -6.98754 -90)
		(property "Reference" "C1G15"
			(at 0 0 270)
			(layer "F.SilkS")
			(hide yes)
			(effects
				(font
					(size 1.27 1.27)
				)
			)
		)
		(property "Value" "*"
			(at -2.3114 0.10795 270)
			(unlocked yes)
			(layer "F.Fab")
			(hide yes)
			(effects
				(font
					(size 0.889 0.889)
					(thickness 0.1524)
				)
			)
		)
		(property "Device Type" "ST270U2D5VBM-GP_SMD-TCG2-ST270A"
			(at -2.3114 -1.41605 270)
			(unlocked yes)
			(layer "F.Fab")
			(hide yes)
			(effects
				(font
					(size 0.889 0.889)
					(thickness 0.1524)
				)
			)
		)
		(duplicate_pad_numbers_are_jumpers no)
		(fp_line
			(start -1.5494 0.4826)
			(end -1.5494 -0.4826)
			(stroke
				(width 0.1524)
				(type default)
			)
			(layer "F.SilkS")
		)
		(fp_line
			(start 1.5494 -0.4826)
			(end 1.5494 0.4826)
			(stroke
				(width 0.1524)
				(type default)
			)
			(layer "F.SilkS")
		)
		(fp_line
			(start -1.0922 -2.35458)
			(end 1.0922 -2.35458)
			(stroke
				(width 0.508)
				(type default)
			)
			(layer "F.SilkS")
		)
		(fp_poly
			(pts
				(xy -1.3462 1.9558) (xy -1.3462 1.905) (xy -1.5494 1.905) (xy -1.5494 -1.905) (xy -1.3462 -1.905)
				(xy -1.3462 -1.9558) (xy 1.3462 -1.9558) (xy 1.3462 -1.905) (xy 1.5494 -1.905) (xy 1.5494 1.905)
				(xy 1.3462 1.905) (xy 1.3462 1.9558)
			)
			(stroke
				(width 0)
				(type default)
			)
			(fill no)
			(layer "F.CrtYd")
		)
		(fp_poly
			(pts
				(xy -1.3462 1.9558) (xy -1.3462 1.905) (xy -1.5494 1.905) (xy -1.5494 -1.905) (xy -1.3462 -1.905)
				(xy -1.3462 -1.9558) (xy 1.3462 -1.9558) (xy 1.3462 -1.905) (xy 1.5494 -1.905) (xy 1.5494 1.905)
				(xy 1.3462 1.905) (xy 1.3462 1.9558)
			)
			(stroke
				(width 0)
				(type default)
			)
			(fill no)
			(layer "F.Fab")
		)
		(pad "1" smd rect
			(at 0 -1.27508 270)
			(size 2.6924 1.3462)
			(layers "F.Cu" "F.Mask" "F.Paste")
			(net "VR_FET_SW_P12V_STBY_PVDDQ_GHJ")
		)
		(pad "2" smd rect
			(at 0 1.27508 270)
			(size 2.6924 1.3462)
			(layers "F.Cu" "F.Mask" "F.Paste")
			(net "GND")
		)
	)
	(footprint ""
		(layer "F.Cu")
		(at 172.280072 -73.839324)
		(property "Reference" "Q4W1"
			(at 0 -1.2065 0)
			(unlocked yes)
			(layer "F.SilkS")
			(effects
				(font
					(size 1.27 0.9652)
					(thickness 0.1524)
				)
				(justify left)
			)
		)
		(property "Value" ""
			(at 0 0 0)
			(layer "F.Fab")
			(effects
				(font
					(size 1.27 1.27)
				)
			)
		)
		(duplicate_pad_numbers_are_jumpers no)
		(fp_circle
			(center -0.643382 -0.50546)
			(end -0.516382 -0.50546)
			(stroke
				(width 0.254)
				(type default)
			)
			(fill no)
			(layer "F.SilkS")
		)
		(fp_poly
			(pts
				(xy 0.21463 -0.450088) (xy 1.56337 -0.450088) (xy 1.56337 1.75006) (xy 0.21463 1.75006)
			)
			(stroke
				(width 0)
				(type default)
			)
			(fill no)
			(layer "F.CrtYd")
		)
		(fp_line
			(start 0.21463 -0.450088)
			(end 1.56337 -0.450088)
			(stroke
				(width 0.1)
				(type default)
			)
			(layer "F.Fab")
		)
		(fp_line
			(start 0.21463 1.75006)
			(end 0.21463 -0.450088)
			(stroke
				(width 0.1)
				(type default)
			)
			(layer "F.Fab")
		)
		(fp_line
			(start 1.56337 -0.450088)
			(end 1.56337 1.75006)
			(stroke
				(width 0.1)
				(type default)
			)
			(layer "F.Fab")
		)
		(fp_line
			(start 1.56337 1.75006)
			(end 0.21463 1.75006)
			(stroke
				(width 0.1)
				(type default)
			)
			(layer "F.Fab")
		)
		(fp_circle
			(center -0.848614 -0.6477)
			(end -0.721614 -0.6477)
			(stroke
				(width 0.254)
				(type default)
			)
			(fill no)
			(layer "F.Fab")
		)
		(pad "1" smd rect
			(at 0 0)
			(size 1.016 0.381)
			(layers "F.Cu" "F.Mask" "F.Paste")
			(net "SMB_HOST_STBY_LVC3_SDA_R2")
		)
		(pad "2" smd rect
			(at 0 0.649986)
			(size 1.016 0.381)
			(layers "F.Cu" "F.Mask" "F.Paste")
			(net "P3V3_DB1200_R1")
		)
		(pad "3" smd rect
			(at 0 1.299972)
			(size 1.016 0.381)
			(layers "F.Cu" "F.Mask" "F.Paste")
			(net "SMB_HOST_STBY_LVC3_SCL")
		)
		(pad "4" smd rect
			(at 1.778 1.299972)
			(size 1.016 0.381)
			(layers "F.Cu" "F.Mask" "F.Paste")
			(net "SMB_HOST_STBY_LVC3_SCL_R2")
		)
		(pad "5" smd rect
			(at 1.778 0.649986)
			(size 1.016 0.381)
			(layers "F.Cu" "F.Mask" "F.Paste")
			(net "P3V3_DB1200_R1")
		)
		(pad "6" smd rect
			(at 1.778 0)
			(size 1.016 0.381)
			(layers "F.Cu" "F.Mask" "F.Paste")
			(net "SMB_HOST_STBY_LVC3_SDA")
		)
	)
	(footprint ""
		(layer "F.Cu")
		(at 399.9738 -130.1496 180)
		(property "Reference" "C8B2"
			(at 0 0 180)
			(layer "F.SilkS")
			(hide yes)
			(effects
				(font
					(size 1.27 1.27)
				)
			)
		)
		(property "Value" ""
			(at 0 0 180)
			(layer "F.Fab")
			(effects
				(font
					(size 1.27 1.27)
				)
			)
		)
		(duplicate_pad_numbers_are_jumpers no)
		(fp_poly
			(pts
				(xy -0.4953 -0.2032) (xy 0.4953 -0.2032) (xy 0.4953 1.6002) (xy -0.4953 1.6002)
			)
			(stroke
				(width 0)
				(type default)
			)
			(fill no)
			(layer "F.CrtYd")
		)
		(fp_line
			(start 0.4953 1.6002)
			(end -0.4953 1.6002)
			(stroke
				(width 0.1)
				(type default)
			)
			(layer "F.Fab")
		)
		(fp_line
			(start 0.4953 -0.2032)
			(end 0.4953 1.6002)
			(stroke
				(width 0.1)
				(type default)
			)
			(layer "F.Fab")
		)
		(fp_line
			(start -0.4953 1.6002)
			(end -0.4953 -0.2032)
			(stroke
				(width 0.1)
				(type default)
			)
			(layer "F.Fab")
		)
		(fp_line
			(start -0.4953 -0.2032)
			(end 0.4953 -0.2032)
			(stroke
				(width 0.1)
				(type default)
			)
			(layer "F.Fab")
		)
		(pad "1" smd rect
			(at 0 0 180)
			(size 0.762 0.889)
			(layers "F.Cu" "F.Mask" "F.Paste")
			(net "P1V8_PCH_STBY")
		)
		(pad "2" smd rect
			(at 0 1.397 180)
			(size 0.762 0.889)
			(layers "F.Cu" "F.Mask" "F.Paste")
			(net "GND")
		)
		(zone
			(layer "F.Cu")
			(hatch none 0.5)
			(connect_pads
				(clearance 0)
			)
			(min_thickness 0.25)
			(keepout
				(tracks not_allowed)
				(vias allowed)
				(pads allowed)
				(copperpour not_allowed)
				(footprints allowed)
			)
			(placement
				(enabled no)
				(sheetname "")
			)
			(fill
				(thermal_gap 0.5)
				(thermal_bridge_width 0.5)
				(island_removal_mode 0)
			)
			(polygon
				(pts
					(xy 400.3548 -130.5941) (xy 399.5928 -130.5941) (xy 399.5928 -131.1021) (xy 400.3548 -131.1021)
				)
			)
		)
	)
	(footprint ""
		(layer "F.Cu")
		(at 279.82545 -70.438518 90)
		(property "Reference" "R6D12"
			(at 0 0 90)
			(layer "F.SilkS")
			(hide yes)
			(effects
				(font
					(size 1.27 1.27)
				)
			)
		)
		(property "Value" ""
			(at 0 0 90)
			(layer "F.Fab")
			(effects
				(font
					(size 1.27 1.27)
				)
			)
		)
		(duplicate_pad_numbers_are_jumpers no)
		(fp_poly
			(pts
				(xy -0.2794 -0.1016) (xy 0.2794 -0.1016) (xy 0.2794 0.9906) (xy -0.2794 0.9906)
			)
			(stroke
				(width 0)
				(type default)
			)
			(fill no)
			(layer "F.CrtYd")
		)
		(fp_line
			(start 0.2794 -0.1016)
			(end -0.2794 -0.1016)
			(stroke
				(width 0.1)
				(type default)
			)
			(layer "F.Fab")
		)
		(fp_line
			(start -0.2794 -0.1016)
			(end -0.2794 0.9906)
			(stroke
				(width 0.1)
				(type default)
			)
			(layer "F.Fab")
		)
		(fp_line
			(start 0.2794 0.9906)
			(end 0.2794 -0.1016)
			(stroke
				(width 0.1)
				(type default)
			)
			(layer "F.Fab")
		)
		(fp_line
			(start -0.2794 0.9906)
			(end 0.2794 0.9906)
			(stroke
				(width 0.1)
				(type default)
			)
			(layer "F.Fab")
		)
		(pad "1" smd rect
			(at 0 0 90)
			(size 0.508 0.508)
			(layers "F.Cu" "F.Mask" "F.Paste")
			(net "PVCCIO_CPU0")
		)
		(pad "2" smd rect
			(at 0 0.889 90)
			(size 0.508 0.508)
			(layers "F.Cu" "F.Mask" "F.Paste")
			(net "RST_CPU0_G_N")
		)
		(zone
			(layer "F.Cu")
			(hatch none 0.5)
			(connect_pads
				(clearance 0)
			)
			(min_thickness 0.25)
			(keepout
				(tracks allowed)
				(vias not_allowed)
				(pads allowed)
				(copperpour not_allowed)
				(footprints allowed)
			)
			(placement
				(enabled no)
				(sheetname "")
			)
			(fill
				(thermal_gap 0.5)
				(thermal_bridge_width 0.5)
				(island_removal_mode 0)
			)
			(polygon
				(pts
					(xy 280.07945 -70.184518) (xy 280.07945 -70.692518) (xy 280.46045 -70.692518) (xy 280.46045 -70.184518)
				)
			)
		)
		(zone
			(layer "F.Cu")
			(hatch none 0.5)
			(connect_pads
				(clearance 0)
			)
			(min_thickness 0.25)
			(keepout
				(tracks not_allowed)
				(vias allowed)
				(pads allowed)
				(copperpour not_allowed)
				(footprints allowed)
			)
			(placement
				(enabled no)
				(sheetname "")
			)
			(fill
				(thermal_gap 0.5)
				(thermal_bridge_width 0.5)
				(island_removal_mode 0)
			)
			(polygon
				(pts
					(xy 280.46045 -70.184518) (xy 280.46045 -70.692518) (xy 280.07945 -70.692518) (xy 280.07945 -70.184518)
				)
			)
		)
	)
	(footprint ""
		(layer "F.Cu")
		(at 40.036496 -73.287382)
		(property "Reference" "L1D2"
			(at 3.378708 -4.251706 0)
			(unlocked yes)
			(layer "F.SilkS")
			(effects
				(font
					(size 0.4064 0.254)
					(thickness 0.1524)
				)
			)
		)
		(property "Value" ""
			(at 0 0 0)
			(layer "F.Fab")
			(effects
				(font
					(size 1.27 1.27)
				)
			)
		)
		(duplicate_pad_numbers_are_jumpers no)
		(fp_line
			(start -1.1303 -3.199892)
			(end 8.3693 -3.199892)
			(stroke
				(width 0.1524)
				(type default)
			)
			(layer "F.SilkS")
		)
		(fp_line
			(start -1.1303 -1.6637)
			(end -1.1303 -3.199892)
			(stroke
				(width 0.1524)
				(type default)
			)
			(layer "F.SilkS")
		)
		(fp_line
			(start -1.1303 3.199892)
			(end -1.1303 1.6637)
			(stroke
				(width 0.1524)
				(type default)
			)
			(layer "F.SilkS")
		)
		(fp_line
			(start 8.3693 -3.199892)
			(end 8.3693 -1.6637)
			(stroke
				(width 0.1524)
				(type default)
			)
			(layer "F.SilkS")
		)
		(fp_line
			(start 8.3693 1.6637)
			(end 8.3693 3.199892)
			(stroke
				(width 0.1524)
				(type default)
			)
			(layer "F.SilkS")
		)
		(fp_line
			(start 8.3693 3.199892)
			(end -1.1303 3.199892)
			(stroke
				(width 0.1524)
				(type default)
			)
			(layer "F.SilkS")
		)
		(fp_rect
			(start -1.1303 3.199892)
			(end 8.3693 -3.199892)
			(stroke
				(width 0)
				(type default)
			)
			(fill no)
			(layer "F.CrtYd")
		)
		(fp_line
			(start -1.1303 -3.199892)
			(end 8.3693 -3.199892)
			(stroke
				(width 0.1)
				(type default)
			)
			(layer "F.Fab")
		)
		(fp_line
			(start -1.1303 3.199892)
			(end -1.1303 -3.199892)
			(stroke
				(width 0.1)
				(type default)
			)
			(layer "F.Fab")
		)
		(fp_line
			(start 8.3693 -3.199892)
			(end 8.3693 3.199892)
			(stroke
				(width 0.1)
				(type default)
			)
			(layer "F.Fab")
		)
		(fp_line
			(start 8.3693 3.199892)
			(end -1.1303 3.199892)
			(stroke
				(width 0.1)
				(type default)
			)
			(layer "F.Fab")
		)
		(pad "1" smd rect
			(at 0 0)
			(size 3.683 2.667)
			(layers "F.Cu" "F.Mask" "F.Paste")
			(net "VR_PVCCIN_CPU1_PHASE3")
		)
		(pad "2" smd rect
			(at 7.239 0)
			(size 3.683 2.667)
			(layers "F.Cu" "F.Mask" "F.Paste")
			(net "PVCCIN_CPU1")
		)
	)
	(footprint ""
		(layer "F.Cu")
		(at 351.028 -130.048 90)
		(property "Reference" "C7B8"
			(at 0 0 90)
			(layer "F.SilkS")
			(hide yes)
			(effects
				(font
					(size 1.27 1.27)
				)
			)
		)
		(property "Value" "*"
			(at -0.0762 -6.2357 90)
			(unlocked yes)
			(layer "F.Fab")
			(hide yes)
			(effects
				(font
					(size 1.27 1.016)
					(thickness 0.1524)
				)
			)
		)
		(property "Device Type" "SC22U16V5MX-4-GP_SMD-BCG5-SC22A"
			(at -0.0762 -8.2677 90)
			(unlocked yes)
			(layer "F.Fab")
			(hide yes)
			(effects
				(font
					(size 1.27 1.016)
					(thickness 0.1524)
				)
			)
		)
		(duplicate_pad_numbers_are_jumpers no)
		(fp_line
			(start 0.635 0)
			(end -0.635 0)
			(stroke
				(width 0.508)
				(type default)
			)
			(layer "F.SilkS")
		)
		(fp_rect
			(start -0.9652 1.778)
			(end 0.9652 -1.778)
			(stroke
				(width 0)
				(type default)
			)
			(fill no)
			(layer "F.CrtYd")
		)
		(fp_poly
			(pts
				(xy -0.9652 -1.778) (xy 0.9652 -1.778) (xy 0.9652 1.778) (xy -0.9652 1.778)
			)
			(stroke
				(width 0)
				(type default)
			)
			(fill no)
			(layer "F.Fab")
		)
		(pad "1" smd rect
			(at 0 -0.9652 90)
			(size 1.397 1.143)
			(layers "F.Cu" "F.Mask" "F.Paste")
			(net "VR_FET_SW_P12V_STBY_PVPP_DEF")
		)
		(pad "2" smd rect
			(at 0 0.9652 90)
			(size 1.397 1.143)
			(layers "F.Cu" "F.Mask" "F.Paste")
			(net "GND")
		)
	)
	(footprint ""
		(layer "F.Cu")
		(at 408.30373 -100.185982 -90)
		(property "Reference" "Y8C1"
			(at 2.8956 1.09347 270)
			(unlocked yes)
			(layer "F.SilkS")
			(effects
				(font
					(size 0.7874 0.5842)
					(thickness 0.1524)
				)
				(justify left)
			)
		)
		(property "Value" ""
			(at 0 0 270)
			(layer "F.Fab")
			(effects
				(font
					(size 1.27 1.27)
				)
			)
		)
		(duplicate_pad_numbers_are_jumpers no)
		(fp_circle
			(center -0.942594 -0.103378)
			(end -0.942594 -0.230378)
			(stroke
				(width 0.254)
				(type default)
			)
			(fill no)
			(layer "F.SilkS")
		)
		(fp_rect
			(start -0.499872 2.70002)
			(end 2.100072 -0.599948)
			(stroke
				(width 0)
				(type default)
			)
			(fill no)
			(layer "F.CrtYd")
		)
		(fp_line
			(start -0.499872 2.70002)
			(end -0.499872 -0.599948)
			(stroke
				(width 0.1)
				(type default)
			)
			(layer "F.Fab")
		)
		(fp_line
			(start 2.100072 2.70002)
			(end -0.499872 2.70002)
			(stroke
				(width 0.1)
				(type default)
			)
			(layer "F.Fab")
		)
		(fp_line
			(start -0.499872 -0.599948)
			(end 2.100072 -0.599948)
			(stroke
				(width 0.1)
				(type default)
			)
			(layer "F.Fab")
		)
		(fp_line
			(start 2.100072 -0.599948)
			(end 2.100072 2.70002)
			(stroke
				(width 0.1)
				(type default)
			)
			(layer "F.Fab")
		)
		(fp_circle
			(center -1.049782 -0.44323)
			(end -1.049782 -0.57023)
			(stroke
				(width 0.254)
				(type default)
			)
			(fill no)
			(layer "F.Fab")
		)
		(pad "1" smd rect
			(at 0 0 270)
			(size 1.0414 1.143)
			(layers "F.Cu" "F.Mask" "F.Paste")
			(net "XTAL_KR_25M_IN")
		)
		(pad "2" smd rect
			(at 0 2.100072 270)
			(size 1.0414 1.143)
			(layers "F.Cu" "F.Mask" "F.Paste")
			(net "GND")
		)
		(pad "3" smd rect
			(at 1.6002 2.100072 270)
			(size 1.0414 1.143)
			(layers "F.Cu" "F.Mask" "F.Paste")
			(net "XTAL_KR_25M_OUT")
		)
		(pad "4" smd rect
			(at 1.6002 0 270)
			(size 1.0414 1.143)
			(layers "F.Cu" "F.Mask" "F.Paste")
			(net "GND")
		)
	)
)
